# T6G (Grand Teton) — schematic netlist excerpt (pin names and nets, part order shuffled) for the footprints in the layout excerpt that follows; sources: Cadence DE-HDL packaged netlist, KiCad conversion of 04192023_DAF0TMB3IC0_F0TG_MB_C_brd_V02_OCP.brd

R6310  Q_RES  0 5% CHIP  pkg 0402LF  page 178 : A = USB_HUB2_TI_OVERCUR1 ; B = USB_HUB2_TI_OVERCUR1_MRP_PROG_FUNC4
R901  Q_RES  0 5% CHIP  pkg 0201LF  page 353 : A = RST_RT_CPU1_P3_RESET_N ; B = RST_RT_CPU1_P3_RESET_R_N
R608  Q_RES  33 5% CHIP  pkg 0402LF  page 77 : A = SPI_CPU0_LVC3_R_TPM_CS_N ; B = SPI_CPU0_LVC3_TPM_CS_N

(kicad_pcb
	(version 20260206)
	(generator "pcbnew")
	(generator_version "10.0")
	(general
		(thickness 1.6)
		(legacy_teardrops no)
	)
	(paper "A4")
	(title_block
		(title "04192023_DAF0TMB3IC0_F0TG_MB_C_brd_V02_OCP.brd")
		(comment 1 "Grand Teton / footprints 3983-3985 of 8354")
	)
	(layers
		(0 "F.Cu" signal "TOP")
		(4 "In1.Cu" signal "GND")
		(6 "In2.Cu" signal "IN1")
		(8 "In3.Cu" signal "GND1")
		(10 "In4.Cu" signal "IN2")
		(12 "In5.Cu" signal "GND2")
		(14 "In6.Cu" signal "IN3")
		(16 "In7.Cu" signal "GND3")
		(18 "In8.Cu" signal "VCC")
		(20 "In9.Cu" signal "VCC1")
		(22 "In10.Cu" signal "GND4")
		(24 "In11.Cu" signal "IN4")
		(26 "In12.Cu" signal "GND5")
		(28 "In13.Cu" signal "IN5")
		(30 "In14.Cu" signal "GND6")
		(32 "In15.Cu" signal "IN6")
		(34 "In16.Cu" signal "GND7")
		(2 "B.Cu" signal "BOTTOM")
		(9 "F.Adhes" user "F.Adhesive")
		(11 "B.Adhes" user "B.Adhesive")
		(13 "F.Paste" user "Package Geometry/Pastemask Top")
		(15 "B.Paste" user "Package Geometry/Pastemask Bottom")
		(5 "F.SilkS" user "Ref Des/Silkscreen Top")
		(7 "B.SilkS" user "Ref Des/Silkscreen Bottom")
		(1 "F.Mask" user "Board Geometry/Soldermask Top")
		(3 "B.Mask" user "Board Geometry/Soldermask Bottom")
		(17 "Dwgs.User" user "User.Drawings")
		(19 "Cmts.User" user "User.Comments")
		(21 "Eco1.User" user "User.Eco1")
		(23 "Eco2.User" user "User.Eco2")
		(25 "Edge.Cuts" user "Board Geometry/Outline")
		(27 "Margin" user)
		(31 "F.CrtYd" user "Package Geometry/Place Bound Top")
		(29 "B.CrtYd" user "Package Geometry/Place Bound Bottom")
		(35 "F.Fab" user "Ref Des/Assembly Top")
		(33 "B.Fab" user "Ref Des/Assembly Bottom")
	)
	(footprint ""
		(layer "F.Cu")
		(at 253.506224 -134.892796 180)
		(property "Reference" "R608"
			(at 0 0 180)
			(layer "F.SilkS")
			(hide yes)
			(effects
				(font
					(size 1.27 1.27)
				)
			)
		)
		(property "Value" ""
			(at 0 0 180)
			(layer "F.Fab")
			(effects
				(font
					(size 1.27 1.27)
				)
			)
		)
		(duplicate_pad_numbers_are_jumpers no)
		(fp_line
			(start 0.7874 0.4064)
			(end -0.7874 0.4064)
			(stroke
				(width 0.1524)
				(type default)
			)
			(layer "F.SilkS")
		)
		(fp_line
			(start 0.7874 -0.4064)
			(end 0.7874 0.4064)
			(stroke
				(width 0.1524)
				(type default)
			)
			(layer "F.SilkS")
		)
		(fp_line
			(start -0.7874 0.4064)
			(end -0.7874 -0.4064)
			(stroke
				(width 0.1524)
				(type default)
			)
			(layer "F.SilkS")
		)
		(fp_line
			(start -0.7874 -0.4064)
			(end 0.7874 -0.4064)
			(stroke
				(width 0.1524)
				(type default)
			)
			(layer "F.SilkS")
		)
		(fp_line
			(start 0.67945 0.3048)
			(end 0.120396 0.3048)
			(stroke
				(width 0.1)
				(type default)
			)
			(layer "F.Fab")
		)
		(fp_line
			(start 0.67945 -0.3048)
			(end 0.67945 0.3048)
			(stroke
				(width 0.1)
				(type default)
			)
			(layer "F.Fab")
		)
		(fp_line
			(start 0.12065 -0.2794)
			(end 0.12065 -0.3048)
			(stroke
				(width 0.1)
				(type default)
			)
			(layer "F.Fab")
		)
		(fp_line
			(start 0.12065 -0.3048)
			(end 0.67945 -0.3048)
			(stroke
				(width 0.1)
				(type default)
			)
			(layer "F.Fab")
		)
		(fp_line
			(start 0.120396 0.3048)
			(end 0.120396 0.2794)
			(stroke
				(width 0.1)
				(type default)
			)
			(layer "F.Fab")
		)
		(fp_line
			(start 0.120396 0.2794)
			(end -0.12065 0.2794)
			(stroke
				(width 0.1)
				(type default)
			)
			(layer "F.Fab")
		)
		(fp_line
			(start -0.12065 0.3048)
			(end -0.67945 0.3048)
			(stroke
				(width 0.1)
				(type default)
			)
			(layer "F.Fab")
		)
		(fp_line
			(start -0.12065 0.2794)
			(end -0.12065 0.3048)
			(stroke
				(width 0.1)
				(type default)
			)
			(layer "F.Fab")
		)
		(fp_line
			(start -0.12065 -0.2794)
			(end 0.12065 -0.2794)
			(stroke
				(width 0.1)
				(type default)
			)
			(layer "F.Fab")
		)
		(fp_line
			(start -0.12065 -0.305054)
			(end -0.12065 -0.2794)
			(stroke
				(width 0.1)
				(type default)
			)
			(layer "F.Fab")
		)
		(fp_line
			(start -0.67945 0.3048)
			(end -0.67945 -0.305054)
			(stroke
				(width 0.1)
				(type default)
			)
			(layer "F.Fab")
		)
		(fp_line
			(start -0.67945 -0.305054)
			(end -0.12065 -0.305054)
			(stroke
				(width 0.1)
				(type default)
			)
			(layer "F.Fab")
		)
		(pad "1" smd circle
			(at -0.40005 0 180)
			(size 0 0)
			(layers "F.Cu" "F.Mask" "F.Paste")
			(net "SPI_CPU0_LVC3_R_TPM_CS_N")
		)
		(pad "2" smd circle
			(at 0.40005 0 180)
			(size 0 0)
			(layers "F.Cu" "F.Mask" "F.Paste")
			(net "SPI_CPU0_LVC3_TPM_CS_N")
		)
	)
	(footprint ""
		(layer "F.Cu")
		(at 110.620302 -389.316976 90)
		(property "Reference" "R901"
			(at 0 0 90)
			(layer "F.SilkS")
			(hide yes)
			(effects
				(font
					(size 1.27 1.27)
				)
			)
		)
		(property "Value" ""
			(at 0 0 90)
			(layer "F.Fab")
			(effects
				(font
					(size 1.27 1.27)
				)
			)
		)
		(duplicate_pad_numbers_are_jumpers no)
		(fp_line
			(start 0.32512 -0.175006)
			(end 0.32512 0.175006)
			(stroke
				(width 0.1)
				(type default)
			)
			(layer "F.Fab")
		)
		(fp_line
			(start -0.32512 -0.175006)
			(end 0.32512 -0.175006)
			(stroke
				(width 0.1)
				(type default)
			)
			(layer "F.Fab")
		)
		(fp_line
			(start 0.32512 0.175006)
			(end -0.32512 0.175006)
			(stroke
				(width 0.1)
				(type default)
			)
			(layer "F.Fab")
		)
		(fp_line
			(start -0.32512 0.175006)
			(end -0.32512 -0.175006)
			(stroke
				(width 0.1)
				(type default)
			)
			(layer "F.Fab")
		)
		(pad "1" smd rect
			(at -0.2667 0 90)
			(size 0.3048 0.381)
			(layers "F.Cu" "F.Mask" "F.Paste")
			(net "RST_RT_CPU1_P3_RESET_N")
		)
		(pad "2" smd rect
			(at 0.2667 0 270)
			(size 0.3048 0.381)
			(layers "F.Cu" "F.Mask" "F.Paste")
			(net "RST_RT_CPU1_P3_RESET_R_N")
		)
	)
	(footprint ""
		(layer "F.Cu")
		(at 108.533946 -52.86248 -90)
		(property "Reference" "R6310"
			(at 0 0 270)
			(layer "F.SilkS")
			(hide yes)
			(effects
				(font
					(size 1.27 1.27)
				)
			)
		)
		(property "Value" ""
			(at 0 0 270)
			(layer "F.Fab")
			(effects
				(font
					(size 1.27 1.27)
				)
			)
		)
		(duplicate_pad_numbers_are_jumpers no)
		(fp_line
			(start -0.7874 0.4064)
			(end -0.7874 -0.4064)
			(stroke
				(width 0.1524)
				(type default)
			)
			(layer "F.SilkS")
		)
		(fp_line
			(start 0.7874 0.4064)
			(end -0.7874 0.4064)
			(stroke
				(width 0.1524)
				(type default)
			)
			(layer "F.SilkS")
		)
		(fp_line
			(start -0.7874 -0.4064)
			(end 0.7874 -0.4064)
			(stroke
				(width 0.1524)
				(type default)
			)
			(layer "F.SilkS")
		)
		(fp_line
			(start 0.7874 -0.4064)
			(end 0.7874 0.4064)
			(stroke
				(width 0.1524)
				(type default)
			)
			(layer "F.SilkS")
		)
		(fp_line
			(start -0.67945 0.3048)
			(end -0.67945 -0.305054)
			(stroke
				(width 0.1)
				(type default)
			)
			(layer "F.Fab")
		)
		(fp_line
			(start -0.12065 0.3048)
			(end -0.67945 0.3048)
			(stroke
				(width 0.1)
				(type default)
			)
			(layer "F.Fab")
		)
		(fp_line
			(start 0.120396 0.3048)
			(end 0.120396 0.2794)
			(stroke
				(width 0.1)
				(type default)
			)
			(layer "F.Fab")
		)
		(fp_line
			(start 0.67945 0.3048)
			(end 0.120396 0.3048)
			(stroke
				(width 0.1)
				(type default)
			)
			(layer "F.Fab")
		)
		(fp_line
			(start -0.12065 0.2794)
			(end -0.12065 0.3048)
			(stroke
				(width 0.1)
				(type default)
			)
			(layer "F.Fab")
		)
		(fp_line
			(start 0.120396 0.2794)
			(end -0.12065 0.2794)
			(stroke
				(width 0.1)
				(type default)
			)
			(layer "F.Fab")
		)
		(fp_line
			(start -0.12065 -0.2794)
			(end 0.12065 -0.2794)
			(stroke
				(width 0.1)
				(type default)
			)
			(layer "F.Fab")
		)
		(fp_line
			(start 0.12065 -0.2794)
			(end 0.12065 -0.3048)
			(stroke
				(width 0.1)
				(type default)
			)
			(layer "F.Fab")
		)
		(fp_line
			(start 0.12065 -0.3048)
			(end 0.67945 -0.3048)
			(stroke
				(width 0.1)
				(type default)
			)
			(layer "F.Fab")
		)
		(fp_line
			(start 0.67945 -0.3048)
			(end 0.67945 0.3048)
			(stroke
				(width 0.1)
				(type default)
			)
			(layer "F.Fab")
		)
		(fp_line
			(start -0.67945 -0.305054)
			(end -0.12065 -0.305054)
			(stroke
				(width 0.1)
				(type default)
			)
			(layer "F.Fab")
		)
		(fp_line
			(start -0.12065 -0.305054)
			(end -0.12065 -0.2794)
			(stroke
				(width 0.1)
				(type default)
			)
			(layer "F.Fab")
		)
		(pad "1" smd circle
			(at -0.40005 0 270)
			(size 0 0)
			(layers "F.Cu" "F.Mask" "F.Paste")
			(net "USB_HUB2_TI_OVERCUR1")
		)
		(pad "2" smd circle
			(at 0.40005 0 270)
			(size 0 0)
			(layers "F.Cu" "F.Mask" "F.Paste")
			(net "USB_HUB2_TI_OVERCUR1_MRP_PROG_FUNC4")
		)
	)
)
